# BASEBOARD_FAB2 (Tioga Pass) — schematic netlist excerpt (pin names and nets, part order shuffled) for the footprints in the layout excerpt that follows; sources: Cadence DE-HDL packaged netlist, KiCad conversion of Wiwynn_Tioga_Pass_MB.brd

R6P39  RES  4.75K 1% CHIP  pkg 0402  page 55 : A = P3V3_STBY ; B = FM_CPU1_SKTOCC_LVT3_N

T1D3  TEST-PAD-12P-1-GP-U  pkg DISCRET-GB1  page 257
  DP  = L3_85OHM_5INCH_DP
  DN  = L3_85OHM_5INCH_DN
  GND(0)  = GND
  GND(1)  = GND
  GND(2)  = GND
  GND(3)  = GND
  GND(4)  = GND
  GND(5)  = GND
  GND(6)  = GND
  GND(7)  = GND
  GND(8)  = GND
  GND(9)  = GND

(kicad_pcb
	(version 20260206)
	(generator "pcbnew")
	(generator_version "10.0")
	(general
		(thickness 1.6)
		(legacy_teardrops no)
	)
	(paper "A4")
	(title_block
		(title "Wiwynn_Tioga_Pass_MB.brd")
		(comment 1 "Tioga Pass / footprints 4235-4236 of 4770")
	)
	(layers
		(0 "F.Cu" signal "TOP")
		(4 "In1.Cu" signal "L2GND")
		(6 "In2.Cu" signal "L3")
		(8 "In3.Cu" signal "L4GND")
		(10 "In4.Cu" signal "L5")
		(12 "In5.Cu" signal "L6GND")
		(14 "In6.Cu" signal "L7VCC")
		(16 "In7.Cu" signal "L8VCC")
		(18 "In8.Cu" signal "L9GND")
		(20 "In9.Cu" signal "L10")
		(22 "In10.Cu" signal "L11GND")
		(24 "In11.Cu" signal "L12")
		(26 "In12.Cu" signal "L13GND")
		(2 "B.Cu" signal "BOTTOM")
		(9 "F.Adhes" user "F.Adhesive")
		(11 "B.Adhes" user "B.Adhesive")
		(13 "F.Paste" user "Package Geometry/Pastemask Top")
		(15 "B.Paste" user "Package Geometry/Pastemask Bottom")
		(5 "F.SilkS" user "Ref Des/Silkscreen Top")
		(7 "B.SilkS" user "Ref Des/Silkscreen Bottom")
		(1 "F.Mask" user "Board Geometry/Soldermask Top")
		(3 "B.Mask" user "Board Geometry/Soldermask Bottom")
		(17 "Dwgs.User" user "User.Drawings")
		(19 "Cmts.User" user "User.Comments")
		(21 "Eco1.User" user "User.Eco1")
		(23 "Eco2.User" user "User.Eco2")
		(25 "Edge.Cuts" user "Board Geometry/Outline")
		(27 "Margin" user)
		(31 "F.CrtYd" user "Package Geometry/Place Bound Top")
		(29 "B.CrtYd" user "Package Geometry/Place Bound Bottom")
		(35 "F.Fab" user "Ref Des/Assembly Top")
		(33 "B.Fab" user "Ref Des/Assembly Bottom")
	)
	(footprint ""
		(layer "B.Cu")
		(at 164.084 -67.31)
		(property "Reference" "R6P39"
			(at 0 0 0)
			(layer "B.SilkS")
			(hide yes)
			(effects
				(font
					(size 1.27 1.27)
				)
				(justify mirror)
			)
		)
		(property "Value" ""
			(at 0 0 0)
			(layer "B.Fab")
			(effects
				(font
					(size 1.27 1.27)
				)
				(justify mirror)
			)
		)
		(duplicate_pad_numbers_are_jumpers no)
		(fp_poly
			(pts
				(xy 0.2794 -0.1016) (xy -0.2794 -0.1016) (xy -0.2794 0.9906) (xy 0.2794 0.9906)
			)
			(stroke
				(width 0)
				(type default)
			)
			(fill no)
			(layer "B.CrtYd")
		)
		(fp_line
			(start -0.2794 -0.1016)
			(end 0.2794 -0.1016)
			(stroke
				(width 0.1)
				(type default)
			)
			(layer "B.Fab")
		)
		(fp_line
			(start -0.2794 0.9906)
			(end -0.2794 -0.1016)
			(stroke
				(width 0.1)
				(type default)
			)
			(layer "B.Fab")
		)
		(fp_line
			(start 0.2794 -0.1016)
			(end 0.2794 0.9906)
			(stroke
				(width 0.1)
				(type default)
			)
			(layer "B.Fab")
		)
		(fp_line
			(start 0.2794 0.9906)
			(end -0.2794 0.9906)
			(stroke
				(width 0.1)
				(type default)
			)
			(layer "B.Fab")
		)
		(pad "1" smd rect
			(at 0 0 180)
			(size 0.508 0.508)
			(layers "B.Cu" "B.Mask" "B.Paste")
			(net "P3V3_STBY")
		)
		(pad "2" smd rect
			(at 0 0.889 180)
			(size 0.508 0.508)
			(layers "B.Cu" "B.Mask" "B.Paste")
			(net "FM_CPU1_SKTOCC_LVT3_N")
		)
		(zone
			(layer "B.Cu")
			(hatch none 0.5)
			(connect_pads
				(clearance 0)
			)
			(min_thickness 0.25)
			(keepout
				(tracks allowed)
				(vias not_allowed)
				(pads allowed)
				(copperpour not_allowed)
				(footprints allowed)
			)
			(placement
				(enabled no)
				(sheetname "")
			)
			(fill
				(thermal_gap 0.5)
				(thermal_bridge_width 0.5)
				(island_removal_mode 0)
			)
			(polygon
				(pts
					(xy 164.338 -67.056) (xy 163.83 -67.056) (xy 163.83 -66.675) (xy 164.338 -66.675)
				)
			)
		)
		(zone
			(layer "B.Cu")
			(hatch none 0.5)
			(connect_pads
				(clearance 0)
			)
			(min_thickness 0.25)
			(keepout
				(tracks not_allowed)
				(vias allowed)
				(pads allowed)
				(copperpour not_allowed)
				(footprints allowed)
			)
			(placement
				(enabled no)
				(sheetname "")
			)
			(fill
				(thermal_gap 0.5)
				(thermal_bridge_width 0.5)
				(island_removal_mode 0)
			)
			(polygon
				(pts
					(xy 164.338 -66.675) (xy 163.83 -66.675) (xy 163.83 -67.056) (xy 164.338 -67.056)
				)
			)
		)
	)
	(footprint ""
		(layer "B.Cu")
		(at 61.285628 -165.04158 -90)
		(property "Reference" "T1D3"
			(at 0 0 90)
			(layer "B.SilkS")
			(hide yes)
			(effects
				(font
					(size 1.27 1.27)
				)
				(justify mirror)
			)
		)
		(property "Value" "*"
			(at 3.4036 -4.46405 270)
			(unlocked yes)
			(layer "B.Fab")
			(hide yes)
			(effects
				(font
					(size 0.889 0.889)
					(thickness 0.1524)
				)
				(justify mirror)
			)
		)
		(property "Device Type" "TEST-PAD-12P-1-GP-U_DISCRET-GBA"
			(at 3.4036 -5.98805 270)
			(unlocked yes)
			(layer "B.Fab")
			(hide yes)
			(effects
				(font
					(size 0.889 0.889)
					(thickness 0.1524)
				)
				(justify mirror)
			)
		)
		(duplicate_pad_numbers_are_jumpers no)
		(fp_line
			(start -2.3622 3.4798)
			(end 2.3876 3.4798)
			(stroke
				(width 0.1524)
				(type default)
			)
			(layer "B.SilkS")
		)
		(fp_line
			(start 2.3876 3.4798)
			(end 2.3876 -4.826)
			(stroke
				(width 0.1524)
				(type default)
			)
			(layer "B.SilkS")
		)
		(fp_line
			(start -2.3622 -4.826)
			(end -2.3622 3.4798)
			(stroke
				(width 0.1524)
				(type default)
			)
			(layer "B.SilkS")
		)
		(fp_line
			(start 2.3876 -4.826)
			(end -2.3622 -4.826)
			(stroke
				(width 0.1524)
				(type default)
			)
			(layer "B.SilkS")
		)
		(fp_rect
			(start 2.6416 3.7338)
			(end -2.6162 -5.08)
			(stroke
				(width 0)
				(type default)
			)
			(fill no)
			(layer "B.CrtYd")
		)
		(fp_rect
			(start 2.6416 3.7338)
			(end -2.6162 -5.08)
			(stroke
				(width 0)
				(type default)
			)
			(fill no)
			(layer "B.Fab")
		)
		(pad "1" smd circle
			(at -0.496824 -1.301496 90)
			(size 0.6604 0.6604)
			(layers "B.Cu" "B.Mask" "B.Paste")
			(net "L3_85OHM_5INCH_DP")
		)
		(pad "2" smd circle
			(at 0.503936 -1.301496 90)
			(size 0.6604 0.6604)
			(layers "B.Cu" "B.Mask" "B.Paste")
			(net "L3_85OHM_5INCH_DN")
		)
		(pad "3" smd custom
			(at 0.00889 0.370078 90)
			(size 0.74295 0.74295)
			(layers "B.Cu" "B.Mask" "B.Paste")
			(net "GND")
			(options
				(clearance outline)
				(anchor circle)
			)
			(primitives
				(gr_poly
					(pts
						(xy -2.1209 -1.4859) (xy 2.1209 -1.4859) (xy 2.1209 1.4859) (xy 1.08585 1.4859) (xy 1.08585 0.4699)
						(xy -1.08585 0.4699) (xy -1.08585 1.4859) (xy -2.1209 1.4859)
					)
					(width 0)
					(fill yes)
				)
			)
		)
		(pad "4" thru_hole circle
			(at -1.266444 -3.851656 90)
			(size 1.4478 1.4478)
			(drill 1.0414)
			(layers "*.Cu" "*.Mask")
			(remove_unused_layers no)
			(net "GND")
			(clearance 0.1524)
			(thermal_gap 0.1524)
		)
		(pad "5" thru_hole circle
			(at 1.273556 -3.851656 90)
			(size 1.4478 1.4478)
			(drill 1.0414)
			(layers "*.Cu" "*.Mask")
			(remove_unused_layers no)
			(net "GND")
			(clearance 0.1524)
			(thermal_gap 0.1524)
		)
		(pad "6" thru_hole circle
			(at -1.266444 2.498344 90)
			(size 1.4478 1.4478)
			(drill 1.0414)
			(layers "*.Cu" "*.Mask")
			(remove_unused_layers no)
			(net "GND")
			(clearance 0.1524)
			(thermal_gap 0.1524)
		)
		(pad "7" thru_hole circle
			(at 1.273556 2.498344 90)
			(size 1.4478 1.4478)
			(drill 1.0414)
			(layers "*.Cu" "*.Mask")
			(remove_unused_layers no)
			(net "GND")
			(clearance 0.1524)
			(thermal_gap 0.1524)
		)
		(pad "8" thru_hole circle
			(at -1.27 -0.4572 90)
			(size 0.7112 0.7112)
			(drill 0.4064)
			(layers "*.Cu" "*.Mask")
			(remove_unused_layers no)
			(net "GND")
			(clearance 0.1016)
			(thermal_gap 0.1016)
		)
		(pad "9" thru_hole circle
			(at -1.27 0.762 90)
			(size 0.7112 0.7112)
			(drill 0.4064)
			(layers "*.Cu" "*.Mask")
			(remove_unused_layers no)
			(net "GND")
			(clearance 0.1016)
			(thermal_gap 0.1016)
		)
		(pad "10" thru_hole circle
			(at 0.0254 0.762 90)
			(size 0.7112 0.7112)
			(drill 0.4064)
			(layers "*.Cu" "*.Mask")
			(remove_unused_layers no)
			(net "GND")
			(clearance 0.1016)
			(thermal_gap 0.1016)
		)
		(pad "11" thru_hole circle
			(at 1.27 0.762 90)
			(size 0.7112 0.7112)
			(drill 0.4064)
			(layers "*.Cu" "*.Mask")
			(remove_unused_layers no)
			(net "GND")
			(clearance 0.1016)
			(thermal_gap 0.1016)
		)
		(pad "12" thru_hole circle
			(at 1.27 -0.4572 90)
			(size 0.7112 0.7112)
			(drill 0.4064)
			(layers "*.Cu" "*.Mask")
			(remove_unused_layers no)
			(net "GND")
			(clearance 0.1016)
			(thermal_gap 0.1016)
		)
	)
)
